(kicad_pcb
	(version 20260206)
	(generator "pcbnew")
	(generator_version "10.0")
	(general
		(thickness 1.6)
		(legacy_teardrops no)
	)
	(paper "A4")
	(title_block
		(title "baseboard — 13948-1b.1110WZS1818.brd")
		(comment 1 "Honey Badger (Wiwynn) / footprints 1420-1424 of 2523")
	)
	(layers
		(0 "F.Cu" signal "TOP")
		(4 "In1.Cu" signal "L2GND")
		(6 "In2.Cu" signal "L3")
		(8 "In3.Cu" signal "L4VCC")
		(10 "In4.Cu" signal "L5VCC")
		(12 "In5.Cu" signal "L6")
		(14 "In6.Cu" signal "L7GND")
		(2 "B.Cu" signal "BOTTOM")
		(9 "F.Adhes" user "F.Adhesive")
		(11 "B.Adhes" user "B.Adhesive")
		(13 "F.Paste" user "Package Geometry/Pastemask Top")
		(15 "B.Paste" user "Package Geometry/Pastemask Bottom")
		(5 "F.SilkS" user "Ref Des/Silkscreen Top")
		(7 "B.SilkS" user "Ref Des/Silkscreen Bottom")
		(1 "F.Mask" user "Board Geometry/Soldermask Top")
		(3 "B.Mask" user "Board Geometry/Soldermask Bottom")
		(17 "Dwgs.User" user "User.Drawings")
		(19 "Cmts.User" user "User.Comments")
		(21 "Eco1.User" user "User.Eco1")
		(23 "Eco2.User" user "User.Eco2")
		(25 "Edge.Cuts" user "Board Geometry/Outline")
		(27 "Margin" user)
		(31 "F.CrtYd" user "Package Geometry/Place Bound Top")
		(29 "B.CrtYd" user "Package Geometry/Place Bound Bottom")
		(35 "F.Fab" user "Ref Des/Assembly Top")
		(33 "B.Fab" user "Ref Des/Assembly Bottom")
	)
	(footprint ""
		(layer "F.Cu")
		(at 274.193 -178.689 90)
		(property "Reference" "R367"
			(at 0 0 90)
			(layer "F.SilkS")
			(hide yes)
			(effects
				(font
					(size 1.27 1.27)
				)
			)
		)
		(property "Value" "3K3R2F-2-GP"
			(at 0.064008 -3.993896 90)
			(unlocked yes)
			(layer "F.Fab")
			(hide yes)
			(effects
				(font
					(size 1.016 1.016)
					(thickness 0.1524)
				)
			)
		)
		(property "Device Type" "R402H16"
			(at 0.064008 -5.517896 90)
			(unlocked yes)
			(layer "F.Fab")
			(hide yes)
			(effects
				(font
					(size 1.016 1.016)
					(thickness 0.1524)
				)
			)
		)
		(duplicate_pad_numbers_are_jumpers no)
		(fp_line
			(start 0.508 -0.9398)
			(end -0.508 -0.9398)
			(stroke
				(width 0.1524)
				(type default)
			)
			(layer "F.SilkS")
		)
		(fp_line
			(start -0.508 -0.9398)
			(end -0.508 0.9398)
			(stroke
				(width 0.1524)
				(type default)
			)
			(layer "F.SilkS")
		)
		(fp_rect
			(start -0.508 0.9398)
			(end 0.508 -0.9398)
			(stroke
				(width 0)
				(type default)
			)
			(fill no)
			(layer "F.CrtYd")
		)
		(fp_rect
			(start -0.508 0.9398)
			(end 0.508 -0.9398)
			(stroke
				(width 0)
				(type default)
			)
			(fill no)
			(layer "F.Fab")
		)
		(pad "1" smd custom
			(at 0 -0.4445 90)
			(size 0.1397 0.1397)
			(layers "F.Cu" "F.Mask" "F.Paste")
			(net "P3V3_STBY")
			(options
				(clearance outline)
				(anchor circle)
			)
			(primitives
				(gr_poly
					(pts
						(arc
							(start -0.1778 -0.2794)
							(mid -0.249642 -0.249642)
							(end -0.2794 -0.1778)
						)
						(arc
							(start -0.2794 0.1778)
							(mid -0.249642 0.249642)
							(end -0.1778 0.2794)
						)
						(arc
							(start 0.1778 0.2794)
							(mid 0.249642 0.249642)
							(end 0.2794 0.1778)
						)
						(arc
							(start 0.2794 -0.1778)
							(mid 0.249642 -0.249642)
							(end 0.1778 -0.2794)
						)
					)
					(width 0)
					(fill yes)
				)
			)
		)
		(pad "2" smd custom
			(at 0 0.4445 90)
			(size 0.1397 0.1397)
			(layers "F.Cu" "F.Mask" "F.Paste")
			(net "ROMA7")
			(options
				(clearance outline)
				(anchor circle)
			)
			(primitives
				(gr_poly
					(pts
						(arc
							(start -0.1778 -0.2794)
							(mid -0.249642 -0.249642)
							(end -0.2794 -0.1778)
						)
						(arc
							(start -0.2794 0.1778)
							(mid -0.249642 0.249642)
							(end -0.1778 0.2794)
						)
						(arc
							(start 0.1778 0.2794)
							(mid 0.249642 0.249642)
							(end 0.2794 0.1778)
						)
						(arc
							(start 0.2794 -0.1778)
							(mid 0.249642 -0.249642)
							(end 0.1778 -0.2794)
						)
					)
					(width 0)
					(fill yes)
				)
			)
		)
	)
	(footprint ""
		(layer "F.Cu")
		(at 305.308 -181.61)
		(property "Reference" "TP176"
			(at 0 0 0)
			(layer "F.SilkS")
			(hide yes)
			(effects
				(font
					(size 1.27 1.27)
				)
			)
		)
		(property "Value" "TPAD28"
			(at 0.0127 -1.8034 0)
			(unlocked yes)
			(layer "F.Fab")
			(hide yes)
			(effects
				(font
					(size 1.016 1.016)
					(thickness 0.1524)
				)
			)
		)
		(property "Device Type" "TPAD28"
			(at 0.0127 -3.3274 0)
			(unlocked yes)
			(layer "F.Fab")
			(hide yes)
			(effects
				(font
					(size 1.016 1.016)
					(thickness 0.1524)
				)
			)
		)
		(duplicate_pad_numbers_are_jumpers no)
		(fp_poly
			(pts
				(arc
					(start 0.3556 0)
					(mid -0.3556 0)
					(end 0.3556 0)
				)
			)
			(stroke
				(width 0)
				(type default)
			)
			(fill no)
			(layer "F.CrtYd")
		)
		(fp_poly
			(pts
				(arc
					(start 0.6096 0)
					(mid -0.6096 0)
					(end 0.6096 0)
				)
			)
			(stroke
				(width 0)
				(type default)
			)
			(fill no)
			(layer "F.Fab")
		)
		(pad "1" smd circle
			(at 0 0)
			(size 0.7112 0.7112)
			(layers "F.Cu" "F.Mask" "F.Paste")
			(net "TP_BMC_GPIOM1")
		)
	)
	(footprint ""
		(layer "F.Cu")
		(at 193.167 -17.145 90)
		(property "Reference" "C151"
			(at 0 0 90)
			(layer "F.SilkS")
			(hide yes)
			(effects
				(font
					(size 1.27 1.27)
				)
			)
		)
		(property "Value" "SCD1U16V2KX-3GP"
			(at 1.1811 -2.7051 90)
			(unlocked yes)
			(layer "F.Fab")
			(hide yes)
			(effects
				(font
					(size 1.016 1.016)
					(thickness 0.1524)
				)
			)
		)
		(property "Device Type" "C402H22"
			(at 1.1811 -4.2291 90)
			(unlocked yes)
			(layer "F.Fab")
			(hide yes)
			(effects
				(font
					(size 1.016 1.016)
					(thickness 0.1524)
				)
			)
		)
		(duplicate_pad_numbers_are_jumpers no)
		(fp_rect
			(start -0.4318 0.9525)
			(end 0.4318 -0.9525)
			(stroke
				(width 0)
				(type default)
			)
			(fill no)
			(layer "F.CrtYd")
		)
		(fp_rect
			(start -0.4318 0.9525)
			(end 0.4318 -0.9525)
			(stroke
				(width 0)
				(type default)
			)
			(fill no)
			(layer "F.Fab")
		)
		(pad "1" smd custom
			(at 0 -0.4445 90)
			(size 0.1524 0.1524)
			(layers "F.Cu" "F.Mask" "F.Paste")
			(net "P3V3_STBY")
			(options
				(clearance outline)
				(anchor circle)
			)
			(primitives
				(gr_poly
					(pts
						(arc
							(start 0.3048 -0.2032)
							(mid 0.275042 -0.275042)
							(end 0.2032 -0.3048)
						)
						(arc
							(start -0.2032 -0.3048)
							(mid -0.275042 -0.275042)
							(end -0.3048 -0.2032)
						)
						(arc
							(start -0.3048 0.2032)
							(mid -0.275042 0.275042)
							(end -0.2032 0.3048)
						)
						(arc
							(start 0.2032 0.3048)
							(mid 0.275042 0.275042)
							(end 0.3048 0.2032)
						)
					)
					(width 0)
					(fill yes)
				)
			)
		)
		(pad "2" smd custom
			(at 0 0.4445 90)
			(size 0.1524 0.1524)
			(layers "F.Cu" "F.Mask" "F.Paste")
			(net "GND")
			(options
				(clearance outline)
				(anchor circle)
			)
			(primitives
				(gr_poly
					(pts
						(arc
							(start 0.3048 -0.2032)
							(mid 0.275042 -0.275042)
							(end 0.2032 -0.3048)
						)
						(arc
							(start -0.2032 -0.3048)
							(mid -0.275042 -0.275042)
							(end -0.3048 -0.2032)
						)
						(arc
							(start -0.3048 0.2032)
							(mid -0.275042 0.275042)
							(end -0.2032 0.3048)
						)
						(arc
							(start 0.2032 0.3048)
							(mid 0.275042 0.275042)
							(end 0.3048 0.2032)
						)
					)
					(width 0)
					(fill yes)
				)
			)
		)
	)
	(footprint ""
		(layer "F.Cu")
		(at 229.743 -17.653)
		(property "Reference" "SC1123"
			(at 0 0 0)
			(layer "F.SilkS")
			(hide yes)
			(effects
				(font
					(size 1.27 1.27)
				)
			)
		)
		(property "Value" "SCD1U16V2KX-3GP"
			(at 1.1811 -2.7051 0)
			(unlocked yes)
			(layer "F.Fab")
			(hide yes)
			(effects
				(font
					(size 1.016 1.016)
					(thickness 0.1524)
				)
			)
		)
		(property "Device Type" "C402H22"
			(at 1.1811 -4.2291 0)
			(unlocked yes)
			(layer "F.Fab")
			(hide yes)
			(effects
				(font
					(size 1.016 1.016)
					(thickness 0.1524)
				)
			)
		)
		(duplicate_pad_numbers_are_jumpers no)
		(fp_rect
			(start -0.4318 0.9525)
			(end 0.4318 -0.9525)
			(stroke
				(width 0)
				(type default)
			)
			(fill no)
			(layer "F.CrtYd")
		)
		(fp_rect
			(start -0.4318 0.9525)
			(end 0.4318 -0.9525)
			(stroke
				(width 0)
				(type default)
			)
			(fill no)
			(layer "F.Fab")
		)
		(pad "1" smd custom
			(at 0 -0.4445)
			(size 0.1524 0.1524)
			(layers "F.Cu" "F.Mask" "F.Paste")
			(net "3D3V_ICE")
			(options
				(clearance outline)
				(anchor circle)
			)
			(primitives
				(gr_poly
					(pts
						(arc
							(start 0.3048 -0.2032)
							(mid 0.275042 -0.275042)
							(end 0.2032 -0.3048)
						)
						(arc
							(start -0.2032 -0.3048)
							(mid -0.275042 -0.275042)
							(end -0.3048 -0.2032)
						)
						(arc
							(start -0.3048 0.2032)
							(mid -0.275042 0.275042)
							(end -0.2032 0.3048)
						)
						(arc
							(start 0.2032 0.3048)
							(mid 0.275042 0.275042)
							(end 0.3048 0.2032)
						)
					)
					(width 0)
					(fill yes)
				)
			)
		)
		(pad "2" smd custom
			(at 0 0.4445)
			(size 0.1524 0.1524)
			(layers "F.Cu" "F.Mask" "F.Paste")
			(net "GND")
			(options
				(clearance outline)
				(anchor circle)
			)
			(primitives
				(gr_poly
					(pts
						(arc
							(start 0.3048 -0.2032)
							(mid 0.275042 -0.275042)
							(end 0.2032 -0.3048)
						)
						(arc
							(start -0.2032 -0.3048)
							(mid -0.275042 -0.275042)
							(end -0.3048 -0.2032)
						)
						(arc
							(start -0.3048 0.2032)
							(mid -0.275042 0.275042)
							(end -0.2032 0.3048)
						)
						(arc
							(start 0.2032 0.3048)
							(mid 0.275042 0.275042)
							(end 0.3048 0.2032)
						)
					)
					(width 0)
					(fill yes)
				)
			)
		)
	)
	(footprint ""
		(layer "F.Cu")
		(at 347.091 -108.204)
		(property "Reference" "PC7"
			(at 0 0 0)
			(layer "F.SilkS")
			(hide yes)
			(effects
				(font
					(size 1.27 1.27)
				)
			)
		)
		(property "Value" "SC22U25V5MX-GP"
			(at -0.0762 -6.1214 0)
			(unlocked yes)
			(layer "F.Fab")
			(hide yes)
			(effects
				(font
					(size 1.016 1.016)
					(thickness 0.1524)
				)
			)
		)
		(property "Device Type" "C805H58"
			(at -0.0762 -8.1534 0)
			(unlocked yes)
			(layer "F.Fab")
			(hide yes)
			(effects
				(font
					(size 1.016 1.016)
					(thickness 0.1524)
				)
			)
		)
		(duplicate_pad_numbers_are_jumpers no)
		(fp_line
			(start 0.635 0)
			(end -0.635 0)
			(stroke
				(width 0.508)
				(type default)
			)
			(layer "F.SilkS")
		)
		(fp_rect
			(start -0.9652 1.778)
			(end 0.9652 -1.778)
			(stroke
				(width 0)
				(type default)
			)
			(fill no)
			(layer "F.CrtYd")
		)
		(fp_poly
			(pts
				(xy -0.9652 -1.778) (xy 0.9652 -1.778) (xy 0.9652 1.778) (xy -0.9652 1.778)
			)
			(stroke
				(width 0)
				(type default)
			)
			(fill no)
			(layer "F.Fab")
		)
		(pad "1" smd rect
			(at 0 -0.9652)
			(size 1.397 1.143)
			(layers "F.Cu" "F.Mask" "F.Paste")
			(net "P5V_STBY_VIN")
		)
		(pad "2" smd rect
			(at 0 0.9652)
			(size 1.397 1.143)
			(layers "F.Cu" "F.Mask" "F.Paste")
			(net "GND")
		)
	)
)
